(kicad_pcb
	(version 20260206)
	(generator "pcbnew")
	(generator_version "10.0")
	(general
		(thickness 1.6)
		(legacy_teardrops no)
	)
	(paper "A4")
	(title_block
		(title "9052_F0T_PDB_Converter_Brick_F_V03_1208_1600_OCP.brd")
		(comment 1 "Grand Teton / footprints 79-85 of 578")
	)
	(layers
		(0 "F.Cu" signal "TOP")
		(4 "In1.Cu" signal "GND")
		(6 "In2.Cu" signal "IN1")
		(8 "In3.Cu" signal "GND1")
		(10 "In4.Cu" signal "VCC")
		(12 "In5.Cu" signal "VCC1")
		(14 "In6.Cu" signal "GND2")
		(16 "In7.Cu" signal "IN2")
		(18 "In8.Cu" signal "GND3")
		(2 "B.Cu" signal "BOTTOM")
		(9 "F.Adhes" user "F.Adhesive")
		(11 "B.Adhes" user "B.Adhesive")
		(13 "F.Paste" user "Package Geometry/Pastemask Top")
		(15 "B.Paste" user "Package Geometry/Pastemask Bottom")
		(5 "F.SilkS" user "Ref Des/Silkscreen Top")
		(7 "B.SilkS" user "Ref Des/Silkscreen Bottom")
		(1 "F.Mask" user "Board Geometry/Soldermask Top")
		(3 "B.Mask" user "Board Geometry/Soldermask Bottom")
		(17 "Dwgs.User" user "User.Drawings")
		(19 "Cmts.User" user "User.Comments")
		(21 "Eco1.User" user "User.Eco1")
		(23 "Eco2.User" user "User.Eco2")
		(25 "Edge.Cuts" user "Board Geometry/Outline")
		(27 "Margin" user)
		(31 "F.CrtYd" user "Package Geometry/Place Bound Top")
		(29 "B.CrtYd" user "Package Geometry/Place Bound Bottom")
		(35 "F.Fab" user "Ref Des/Assembly Top")
		(33 "B.Fab" user "Ref Des/Assembly Bottom")
	)
	(footprint ""
		(layer "F.Cu")
		(at 277.114 -138.557 180)
		(property "Reference" "PD8"
			(at -2.921 -3.96367 0)
			(unlocked yes)
			(layer "F.SilkS")
			(effects
				(font
					(size 0.7874 0.5842)
					(thickness 0.1524)
				)
				(justify left)
			)
		)
		(property "Value" ""
			(at 0 0 180)
			(layer "F.Fab")
			(effects
				(font
					(size 1.27 1.27)
				)
			)
		)
		(duplicate_pad_numbers_are_jumpers no)
		(fp_line
			(start 5.334 3.109976)
			(end 5.334 0)
			(stroke
				(width 0.1524)
				(type default)
			)
			(layer "F.SilkS")
		)
		(fp_line
			(start 5.334 3.109976)
			(end 4.8133 3.109976)
			(stroke
				(width 0.1524)
				(type default)
			)
			(layer "F.SilkS")
		)
		(fp_line
			(start 5.334 0)
			(end 5.334 -3.109976)
			(stroke
				(width 0.1524)
				(type default)
			)
			(layer "F.SilkS")
		)
		(fp_line
			(start 5.207 3.109976)
			(end 5.207 -3.109976)
			(stroke
				(width 0.1524)
				(type default)
			)
			(layer "F.SilkS")
		)
		(fp_line
			(start 5.1308 3.109976)
			(end 5.1308 -3.109976)
			(stroke
				(width 0.1524)
				(type default)
			)
			(layer "F.SilkS")
		)
		(fp_line
			(start 5.0292 3.109976)
			(end 5.0292 -3.109976)
			(stroke
				(width 0.1524)
				(type default)
			)
			(layer "F.SilkS")
		)
		(fp_line
			(start 4.9276 3.109976)
			(end 4.9276 -3.109976)
			(stroke
				(width 0.1524)
				(type default)
			)
			(layer "F.SilkS")
		)
		(fp_line
			(start 4.826 3.109976)
			(end -4.826 3.109976)
			(stroke
				(width 0.1524)
				(type default)
			)
			(layer "F.SilkS")
		)
		(fp_line
			(start 4.826 0)
			(end 4.826 3.109976)
			(stroke
				(width 0.1524)
				(type default)
			)
			(layer "F.SilkS")
		)
		(fp_line
			(start 4.826 -3.109976)
			(end 4.826 0)
			(stroke
				(width 0.1524)
				(type default)
			)
			(layer "F.SilkS")
		)
		(fp_line
			(start 4.8133 -3.109976)
			(end 5.3467 -3.109976)
			(stroke
				(width 0.1524)
				(type default)
			)
			(layer "F.SilkS")
		)
		(fp_line
			(start 1.143 1.397)
			(end 1.143 -1.397)
			(stroke
				(width 0.1524)
				(type default)
			)
			(layer "F.SilkS")
		)
		(fp_line
			(start 1.143 0)
			(end 1.8034 0)
			(stroke
				(width 0.1524)
				(type default)
			)
			(layer "F.SilkS")
		)
		(fp_line
			(start 1.143 0)
			(end -1.016 -1.016)
			(stroke
				(width 0.1524)
				(type default)
			)
			(layer "F.SilkS")
		)
		(fp_line
			(start -1.016 1.016)
			(end 1.016 0)
			(stroke
				(width 0.1524)
				(type default)
			)
			(layer "F.SilkS")
		)
		(fp_line
			(start -1.016 -1.016)
			(end -1.016 1.016)
			(stroke
				(width 0.1524)
				(type default)
			)
			(layer "F.SilkS")
		)
		(fp_line
			(start -1.0922 0)
			(end -1.7018 0)
			(stroke
				(width 0.1524)
				(type default)
			)
			(layer "F.SilkS")
		)
		(fp_line
			(start -4.826 3.109976)
			(end -4.826 0)
			(stroke
				(width 0.1524)
				(type default)
			)
			(layer "F.SilkS")
		)
		(fp_line
			(start -4.826 0)
			(end -4.826 -3.109976)
			(stroke
				(width 0.1524)
				(type default)
			)
			(layer "F.SilkS")
		)
		(fp_line
			(start -4.826 -3.109976)
			(end 4.826 -3.109976)
			(stroke
				(width 0.1524)
				(type default)
			)
			(layer "F.SilkS")
		)
		(fp_line
			(start 3.554984 3.109976)
			(end -3.554984 3.109976)
			(stroke
				(width 0.1)
				(type default)
			)
			(layer "F.Fab")
		)
		(fp_line
			(start 3.554984 -3.109976)
			(end 3.554984 3.109976)
			(stroke
				(width 0.1)
				(type default)
			)
			(layer "F.Fab")
		)
		(fp_line
			(start 1.143 1.397)
			(end 1.143 -1.397)
			(stroke
				(width 0.1)
				(type default)
			)
			(layer "F.Fab")
		)
		(fp_line
			(start 1.143 0)
			(end 1.8034 0)
			(stroke
				(width 0.1)
				(type default)
			)
			(layer "F.Fab")
		)
		(fp_line
			(start 1.143 0)
			(end -1.016 -1.016)
			(stroke
				(width 0.1)
				(type default)
			)
			(layer "F.Fab")
		)
		(fp_line
			(start -1.016 1.016)
			(end 1.016 0)
			(stroke
				(width 0.1)
				(type default)
			)
			(layer "F.Fab")
		)
		(fp_line
			(start -1.016 -1.016)
			(end -1.016 1.016)
			(stroke
				(width 0.1)
				(type default)
			)
			(layer "F.Fab")
		)
		(fp_line
			(start -1.0922 0)
			(end -1.7018 0)
			(stroke
				(width 0.1)
				(type default)
			)
			(layer "F.Fab")
		)
		(fp_line
			(start -3.554984 3.109976)
			(end -3.554984 -3.109976)
			(stroke
				(width 0.1)
				(type default)
			)
			(layer "F.Fab")
		)
		(fp_line
			(start -3.554984 -3.109976)
			(end 3.554984 -3.109976)
			(stroke
				(width 0.1)
				(type default)
			)
			(layer "F.Fab")
		)
		(fp_text user "-"
			(at 7.62 0.34925 0)
			(unlocked yes)
			(layer "F.SilkS")
			(effects
				(font
					(size 1.905 1.4224)
					(thickness 0.1524)
				)
				(justify left)
			)
		)
		(fp_text user "+"
			(at -6.731 0.47625 0)
			(unlocked yes)
			(layer "F.SilkS")
			(effects
				(font
					(size 1.905 1.4224)
					(thickness 0.1524)
				)
				(justify left)
			)
		)
		(fp_text user "-"
			(at 6.6802 0.22225 0)
			(unlocked yes)
			(layer "F.Fab")
			(effects
				(font
					(size 1.905 1.4224)
					(thickness 0.1524)
				)
				(justify left)
			)
		)
		(fp_text user "+"
			(at -4.5466 0.19685 0)
			(unlocked yes)
			(layer "F.Fab")
			(effects
				(font
					(size 1.905 1.4224)
					(thickness 0.1524)
				)
				(justify left)
			)
		)
		(pad "A" smd rect
			(at -3.400044 0)
			(size 2.5146 3.302)
			(layers "F.Cu" "F.Mask" "F.Paste")
			(net "GND")
		)
		(pad "C" smd rect
			(at 3.400044 0)
			(size 2.5146 3.302)
			(layers "F.Cu" "F.Mask" "F.Paste")
			(net "P52V_HS")
		)
	)
	(footprint ""
		(layer "F.Cu")
		(at 45.67936 -58.75782)
		(property "Reference" "C96"
			(at 0 0 0)
			(layer "F.SilkS")
			(hide yes)
			(effects
				(font
					(size 1.27 1.27)
				)
			)
		)
		(property "Value" ""
			(at 0 0 0)
			(layer "F.Fab")
			(effects
				(font
					(size 1.27 1.27)
				)
			)
		)
		(duplicate_pad_numbers_are_jumpers no)
		(fp_line
			(start -0.7874 -0.4064)
			(end 0.7874 -0.4064)
			(stroke
				(width 0.1524)
				(type default)
			)
			(layer "F.SilkS")
		)
		(fp_line
			(start -0.7874 0.4064)
			(end -0.7874 -0.4064)
			(stroke
				(width 0.1524)
				(type default)
			)
			(layer "F.SilkS")
		)
		(fp_line
			(start 0.7874 -0.4064)
			(end 0.7874 0.4064)
			(stroke
				(width 0.1524)
				(type default)
			)
			(layer "F.SilkS")
		)
		(fp_line
			(start 0.7874 0.4064)
			(end -0.7874 0.4064)
			(stroke
				(width 0.1524)
				(type default)
			)
			(layer "F.SilkS")
		)
		(fp_line
			(start -0.67945 -0.305054)
			(end -0.12065 -0.305054)
			(stroke
				(width 0.1)
				(type default)
			)
			(layer "F.Fab")
		)
		(fp_line
			(start -0.67945 0.3048)
			(end -0.67945 -0.305054)
			(stroke
				(width 0.1)
				(type default)
			)
			(layer "F.Fab")
		)
		(fp_line
			(start -0.12065 -0.305054)
			(end -0.12065 -0.2794)
			(stroke
				(width 0.1)
				(type default)
			)
			(layer "F.Fab")
		)
		(fp_line
			(start -0.12065 -0.2794)
			(end 0.12065 -0.2794)
			(stroke
				(width 0.1)
				(type default)
			)
			(layer "F.Fab")
		)
		(fp_line
			(start -0.12065 0.2794)
			(end -0.12065 0.3048)
			(stroke
				(width 0.1)
				(type default)
			)
			(layer "F.Fab")
		)
		(fp_line
			(start -0.12065 0.3048)
			(end -0.67945 0.3048)
			(stroke
				(width 0.1)
				(type default)
			)
			(layer "F.Fab")
		)
		(fp_line
			(start 0.120396 0.2794)
			(end -0.12065 0.2794)
			(stroke
				(width 0.1)
				(type default)
			)
			(layer "F.Fab")
		)
		(fp_line
			(start 0.120396 0.3048)
			(end 0.120396 0.2794)
			(stroke
				(width 0.1)
				(type default)
			)
			(layer "F.Fab")
		)
		(fp_line
			(start 0.12065 -0.3048)
			(end 0.67945 -0.3048)
			(stroke
				(width 0.1)
				(type default)
			)
			(layer "F.Fab")
		)
		(fp_line
			(start 0.12065 -0.2794)
			(end 0.12065 -0.3048)
			(stroke
				(width 0.1)
				(type default)
			)
			(layer "F.Fab")
		)
		(fp_line
			(start 0.67945 -0.3048)
			(end 0.67945 0.3048)
			(stroke
				(width 0.1)
				(type default)
			)
			(layer "F.Fab")
		)
		(fp_line
			(start 0.67945 0.3048)
			(end 0.120396 0.3048)
			(stroke
				(width 0.1)
				(type default)
			)
			(layer "F.Fab")
		)
		(pad "1" smd circle
			(at -0.40005 0)
			(size 0 0)
			(layers "F.Cu" "F.Mask" "F.Paste")
			(net "P12V_HPDB_0_SS")
		)
		(pad "2" smd circle
			(at 0.40005 0)
			(size 0 0)
			(layers "F.Cu" "F.Mask" "F.Paste")
			(net "GND")
		)
	)
	(footprint ""
		(layer "F.Cu")
		(at 282.702 -21.082)
		(property "Reference" "C89"
			(at 0 0 0)
			(layer "F.SilkS")
			(hide yes)
			(effects
				(font
					(size 1.27 1.27)
				)
			)
		)
		(property "Value" ""
			(at 0 0 0)
			(layer "F.Fab")
			(effects
				(font
					(size 1.27 1.27)
				)
			)
		)
		(duplicate_pad_numbers_are_jumpers no)
		(fp_line
			(start -1.2954 -0.5842)
			(end 1.2954 -0.5842)
			(stroke
				(width 0.1524)
				(type default)
			)
			(layer "F.SilkS")
		)
		(fp_line
			(start -1.2954 0.5842)
			(end -1.2954 -0.5842)
			(stroke
				(width 0.1524)
				(type default)
			)
			(layer "F.SilkS")
		)
		(fp_line
			(start 1.2954 -0.5842)
			(end 1.2954 0.5842)
			(stroke
				(width 0.1524)
				(type default)
			)
			(layer "F.SilkS")
		)
		(fp_line
			(start 1.2954 0.5842)
			(end -1.2954 0.5842)
			(stroke
				(width 0.1524)
				(type default)
			)
			(layer "F.SilkS")
		)
		(fp_line
			(start -1.1938 -0.4064)
			(end -0.8636 -0.4064)
			(stroke
				(width 0.1)
				(type default)
			)
			(layer "F.Fab")
		)
		(fp_line
			(start -1.1938 0.4064)
			(end -1.1938 -0.4064)
			(stroke
				(width 0.1)
				(type default)
			)
			(layer "F.Fab")
		)
		(fp_line
			(start -0.8636 -0.4572)
			(end 0.8636 -0.4572)
			(stroke
				(width 0.1)
				(type default)
			)
			(layer "F.Fab")
		)
		(fp_line
			(start -0.8636 -0.4064)
			(end -0.8636 -0.4572)
			(stroke
				(width 0.1)
				(type default)
			)
			(layer "F.Fab")
		)
		(fp_line
			(start -0.8636 0.4064)
			(end -1.1938 0.4064)
			(stroke
				(width 0.1)
				(type default)
			)
			(layer "F.Fab")
		)
		(fp_line
			(start -0.8636 0.4572)
			(end -0.8636 0.4064)
			(stroke
				(width 0.1)
				(type default)
			)
			(layer "F.Fab")
		)
		(fp_line
			(start 0.8636 -0.4572)
			(end 0.8636 -0.4064)
			(stroke
				(width 0.1)
				(type default)
			)
			(layer "F.Fab")
		)
		(fp_line
			(start 0.8636 -0.4064)
			(end 1.1938 -0.4064)
			(stroke
				(width 0.1)
				(type default)
			)
			(layer "F.Fab")
		)
		(fp_line
			(start 0.8636 0.4064)
			(end 0.8636 0.4572)
			(stroke
				(width 0.1)
				(type default)
			)
			(layer "F.Fab")
		)
		(fp_line
			(start 0.8636 0.4572)
			(end -0.8636 0.4572)
			(stroke
				(width 0.1)
				(type default)
			)
			(layer "F.Fab")
		)
		(fp_line
			(start 1.1938 -0.4064)
			(end 1.1938 0.4064)
			(stroke
				(width 0.1)
				(type default)
			)
			(layer "F.Fab")
		)
		(fp_line
			(start 1.1938 0.4064)
			(end 0.8636 0.4064)
			(stroke
				(width 0.1)
				(type default)
			)
			(layer "F.Fab")
		)
		(pad "1" smd rect
			(at -0.7366 0 270)
			(size 0.7112 0.8128)
			(layers "F.Cu" "F.Mask" "F.Paste")
			(net "FM_HSC_EN_BUSBAR")
		)
		(pad "2" smd rect
			(at 0.7366 0 270)
			(size 0.7112 0.8128)
			(layers "F.Cu" "F.Mask" "F.Paste")
			(net "GND")
		)
	)
	(footprint ""
		(layer "F.Cu")
		(at 173.609 -49.911)
		(property "Reference" "PC31"
			(at 0 0 0)
			(layer "F.SilkS")
			(hide yes)
			(effects
				(font
					(size 1.27 1.27)
				)
			)
		)
		(property "Value" ""
			(at 0 0 0)
			(layer "F.Fab")
			(effects
				(font
					(size 1.27 1.27)
				)
			)
		)
		(duplicate_pad_numbers_are_jumpers no)
		(fp_line
			(start -1.524 -0.762)
			(end 1.524 -0.762)
			(stroke
				(width 0.1524)
				(type default)
			)
			(layer "F.SilkS")
		)
		(fp_line
			(start -1.524 0.762)
			(end -1.524 -0.762)
			(stroke
				(width 0.1524)
				(type default)
			)
			(layer "F.SilkS")
		)
		(fp_line
			(start 1.524 -0.762)
			(end 1.524 0.762)
			(stroke
				(width 0.1524)
				(type default)
			)
			(layer "F.SilkS")
		)
		(fp_line
			(start 1.524 0.762)
			(end -1.524 0.762)
			(stroke
				(width 0.1524)
				(type default)
			)
			(layer "F.SilkS")
		)
		(fp_line
			(start -1.1049 -0.724916)
			(end -1.1049 0.724916)
			(stroke
				(width 0.1)
				(type default)
			)
			(layer "F.Fab")
		)
		(fp_line
			(start -1.1049 0.724916)
			(end 1.1049 0.724916)
			(stroke
				(width 0.1)
				(type default)
			)
			(layer "F.Fab")
		)
		(fp_line
			(start 1.1049 -0.724916)
			(end -1.1049 -0.724916)
			(stroke
				(width 0.1)
				(type default)
			)
			(layer "F.Fab")
		)
		(fp_line
			(start 1.1049 0.724916)
			(end 1.1049 -0.724916)
			(stroke
				(width 0.1)
				(type default)
			)
			(layer "F.Fab")
		)
		(pad "1" smd rect
			(at -0.889 0 180)
			(size 1.016 1.27)
			(layers "F.Cu" "F.Mask" "F.Paste")
			(net "P12V_BRICK")
		)
		(pad "2" smd rect
			(at 0.889 0 180)
			(size 1.016 1.27)
			(layers "F.Cu" "F.Mask" "F.Paste")
			(net "GND")
		)
	)
	(footprint ""
		(layer "F.Cu")
		(at 44.713906 -127.889)
		(property "Reference" "PC74"
			(at 0 0 0)
			(layer "F.SilkS")
			(hide yes)
			(effects
				(font
					(size 1.27 1.27)
				)
			)
		)
		(property "Value" ""
			(at 0 0 0)
			(layer "F.Fab")
			(effects
				(font
					(size 1.27 1.27)
				)
			)
		)
		(duplicate_pad_numbers_are_jumpers no)
		(fp_line
			(start -2.2098 -0.9398)
			(end 2.2098 -0.9398)
			(stroke
				(width 0.1524)
				(type default)
			)
			(layer "F.SilkS")
		)
		(fp_line
			(start -2.2098 0.9398)
			(end -2.2098 -0.9398)
			(stroke
				(width 0.1524)
				(type default)
			)
			(layer "F.SilkS")
		)
		(fp_line
			(start 2.2098 -0.9398)
			(end 2.2098 0.9398)
			(stroke
				(width 0.1524)
				(type default)
			)
			(layer "F.SilkS")
		)
		(fp_line
			(start 2.2098 0.9398)
			(end -2.2098 0.9398)
			(stroke
				(width 0.1524)
				(type default)
			)
			(layer "F.SilkS")
		)
		(fp_line
			(start -1.700022 -0.899922)
			(end 1.700022 -0.899922)
			(stroke
				(width 0.1)
				(type default)
			)
			(layer "F.Fab")
		)
		(fp_line
			(start -1.700022 0.899922)
			(end -1.700022 -0.899922)
			(stroke
				(width 0.1)
				(type default)
			)
			(layer "F.Fab")
		)
		(fp_line
			(start 1.700022 -0.899922)
			(end 1.700022 0.899922)
			(stroke
				(width 0.1)
				(type default)
			)
			(layer "F.Fab")
		)
		(fp_line
			(start 1.700022 0.899922)
			(end -1.700022 0.899922)
			(stroke
				(width 0.1)
				(type default)
			)
			(layer "F.Fab")
		)
		(pad "1" smd rect
			(at -1.4732 0 180)
			(size 1.1684 1.5748)
			(layers "F.Cu" "F.Mask" "F.Paste")
			(net "P52V_HS_FILTER")
		)
		(pad "2" smd rect
			(at 1.4732 0 180)
			(size 1.1684 1.5748)
			(layers "F.Cu" "F.Mask" "F.Paste")
			(net "GND")
		)
	)
	(footprint ""
		(layer "F.Cu")
		(at 232.156 -95.504 -90)
		(property "Reference" "C37"
			(at 0 0 270)
			(layer "F.SilkS")
			(hide yes)
			(effects
				(font
					(size 1.27 1.27)
				)
			)
		)
		(property "Value" ""
			(at 0 0 270)
			(layer "F.Fab")
			(effects
				(font
					(size 1.27 1.27)
				)
			)
		)
		(duplicate_pad_numbers_are_jumpers no)
		(fp_line
			(start -2.2098 0.9398)
			(end -2.2098 -0.9398)
			(stroke
				(width 0.1524)
				(type default)
			)
			(layer "F.SilkS")
		)
		(fp_line
			(start 2.2098 0.9398)
			(end -2.2098 0.9398)
			(stroke
				(width 0.1524)
				(type default)
			)
			(layer "F.SilkS")
		)
		(fp_line
			(start -2.2098 -0.9398)
			(end 2.2098 -0.9398)
			(stroke
				(width 0.1524)
				(type default)
			)
			(layer "F.SilkS")
		)
		(fp_line
			(start 2.2098 -0.9398)
			(end 2.2098 0.9398)
			(stroke
				(width 0.1524)
				(type default)
			)
			(layer "F.SilkS")
		)
		(fp_line
			(start -1.700022 0.899922)
			(end -1.700022 -0.899922)
			(stroke
				(width 0.1)
				(type default)
			)
			(layer "F.Fab")
		)
		(fp_line
			(start 1.700022 0.899922)
			(end -1.700022 0.899922)
			(stroke
				(width 0.1)
				(type default)
			)
			(layer "F.Fab")
		)
		(fp_line
			(start -1.700022 -0.899922)
			(end 1.700022 -0.899922)
			(stroke
				(width 0.1)
				(type default)
			)
			(layer "F.Fab")
		)
		(fp_line
			(start 1.700022 -0.899922)
			(end 1.700022 0.899922)
			(stroke
				(width 0.1)
				(type default)
			)
			(layer "F.Fab")
		)
		(pad "1" smd rect
			(at -1.4732 0 90)
			(size 1.1684 1.5748)
			(layers "F.Cu" "F.Mask" "F.Paste")
			(net "P52V_HS")
		)
		(pad "2" smd rect
			(at 1.4732 0 90)
			(size 1.1684 1.5748)
			(layers "F.Cu" "F.Mask" "F.Paste")
			(net "GND")
		)
	)
	(footprint ""
		(layer "F.Cu")
		(at 50.1396 -56.8198 -90)
		(property "Reference" "D4"
			(at -4.36753 -1.5494 0)
			(unlocked yes)
			(layer "F.SilkS")
			(effects
				(font
					(size 0.7874 0.5842)
					(thickness 0.1524)
				)
				(justify left)
			)
		)
		(property "Value" ""
			(at 0 0 270)
			(layer "F.Fab")
			(effects
				(font
					(size 1.27 1.27)
				)
			)
		)
		(duplicate_pad_numbers_are_jumpers no)
		(fp_line
			(start -3.656584 1.970024)
			(end 4.240784 1.970024)
			(stroke
				(width 0.1524)
				(type default)
			)
			(layer "F.SilkS")
		)
		(fp_line
			(start 4.240784 1.970024)
			(end 4.240784 -1.970024)
			(stroke
				(width 0.1524)
				(type default)
			)
			(layer "F.SilkS")
		)
		(fp_line
			(start -3.656584 -1.970024)
			(end -3.656584 1.970024)
			(stroke
				(width 0.1524)
				(type default)
			)
			(layer "F.SilkS")
		)
		(fp_line
			(start 4.240784 -1.970024)
			(end -3.656584 -1.970024)
			(stroke
				(width 0.1524)
				(type default)
			)
			(layer "F.SilkS")
		)
		(fp_poly
			(pts
				(xy 3.580384 1.970024) (xy 3.580384 -1.970024) (xy 4.240784 -1.970024) (xy 4.240784 1.970024)
			)
			(stroke
				(width 0)
				(type default)
			)
			(fill yes)
			(layer "F.SilkS")
		)
		(fp_line
			(start -2.3749 1.970024)
			(end 2.3749 1.970024)
			(stroke
				(width 0.1)
				(type default)
			)
			(layer "F.Fab")
		)
		(fp_line
			(start 2.3749 1.970024)
			(end 2.3749 -1.970024)
			(stroke
				(width 0.1)
				(type default)
			)
			(layer "F.Fab")
		)
		(fp_line
			(start -2.3749 -1.970024)
			(end -2.3749 1.970024)
			(stroke
				(width 0.1)
				(type default)
			)
			(layer "F.Fab")
		)
		(fp_line
			(start 2.3749 -1.970024)
			(end -2.3749 -1.970024)
			(stroke
				(width 0.1)
				(type default)
			)
			(layer "F.Fab")
		)
		(fp_text user "+"
			(at -4.9784 -0.23495 270)
			(unlocked yes)
			(layer "F.Fab")
			(effects
				(font
					(size 1.905 1.4224)
					(thickness 0.1524)
				)
				(justify left)
			)
		)
		(fp_text user "-"
			(at 4.1656 -0.23495 270)
			(unlocked yes)
			(layer "F.Fab")
			(effects
				(font
					(size 1.905 1.4224)
					(thickness 0.1524)
				)
				(justify left)
			)
		)
		(pad "A" smd rect
			(at -2.450084 0 270)
			(size 2.159 2.2606)
			(layers "F.Cu" "F.Mask" "F.Paste")
			(net "GND")
		)
		(pad "C" smd rect
			(at 2.450084 0 270)
			(size 2.159 2.2606)
			(layers "F.Cu" "F.Mask" "F.Paste")
			(net "P12V_BRICK")
		)
	)
)
